# S9S_MB_2U (Grand Teton) — schematic netlist excerpt (pin names and nets, part order shuffled) for the footprints in the layout excerpt that follows; sources: Cadence DE-HDL packaged netlist, KiCad conversion of 03242023_DA0F0TMBIJ0_F0T_Motherboard_J_brd_V01_OCP.brd

R4098  Q_RES  10K 1% CHIP  pkg 0402LF  page 183 : A = PD_PCH_GPPC_A_14 ; B = GND
C2452  Q_CAP  1000PF 50V 5% X7R  pkg 0402  page 292 : A = PVCCFA_EHV_CPU1_EN_R ; B = GND

(kicad_pcb
	(version 20260206)
	(generator "pcbnew")
	(generator_version "10.0")
	(general
		(thickness 1.6)
		(legacy_teardrops no)
	)
	(paper "A4")
	(title_block
		(title "03242023_DA0F0TMBIJ0_F0T_Motherboard_J_brd_V01_OCP.brd")
		(comment 1 "Grand Teton / footprints 3258-3259 of 6105")
	)
	(layers
		(0 "F.Cu" signal "TOP")
		(4 "In1.Cu" signal "GND")
		(6 "In2.Cu" signal "IN1")
		(8 "In3.Cu" signal "GND1")
		(10 "In4.Cu" signal "IN2")
		(12 "In5.Cu" signal "GND2")
		(14 "In6.Cu" signal "IN3")
		(16 "In7.Cu" signal "GND3")
		(18 "In8.Cu" signal "VCC")
		(20 "In9.Cu" signal "VCC1")
		(22 "In10.Cu" signal "GND4")
		(24 "In11.Cu" signal "IN4")
		(26 "In12.Cu" signal "GND5")
		(28 "In13.Cu" signal "IN5")
		(30 "In14.Cu" signal "GND6")
		(32 "In15.Cu" signal "IN6")
		(34 "In16.Cu" signal "GND7")
		(2 "B.Cu" signal "BOTTOM")
		(9 "F.Adhes" user "F.Adhesive")
		(11 "B.Adhes" user "B.Adhesive")
		(13 "F.Paste" user "Package Geometry/Pastemask Top")
		(15 "B.Paste" user "Package Geometry/Pastemask Bottom")
		(5 "F.SilkS" user "Ref Des/Silkscreen Top")
		(7 "B.SilkS" user "Ref Des/Silkscreen Bottom")
		(1 "F.Mask" user "Board Geometry/Soldermask Top")
		(3 "B.Mask" user "Board Geometry/Soldermask Bottom")
		(17 "Dwgs.User" user "User.Drawings")
		(19 "Cmts.User" user "User.Comments")
		(21 "Eco1.User" user "User.Eco1")
		(23 "Eco2.User" user "User.Eco2")
		(25 "Edge.Cuts" user "Board Geometry/Outline")
		(27 "Margin" user)
		(31 "F.CrtYd" user "Package Geometry/Place Bound Top")
		(29 "B.CrtYd" user "Package Geometry/Place Bound Bottom")
		(35 "F.Fab" user "Ref Des/Assembly Top")
		(33 "B.Fab" user "Ref Des/Assembly Bottom")
	)
	(footprint ""
		(layer "F.Cu")
		(at 328.123042 -22.674326 -90)
		(property "Reference" "R4098"
			(at 0 0 270)
			(layer "F.SilkS")
			(hide yes)
			(effects
				(font
					(size 1.27 1.27)
				)
			)
		)
		(property "Value" ""
			(at 0 0 270)
			(layer "F.Fab")
			(effects
				(font
					(size 1.27 1.27)
				)
			)
		)
		(duplicate_pad_numbers_are_jumpers no)
		(fp_line
			(start -0.7874 0.4064)
			(end -0.7874 -0.4064)
			(stroke
				(width 0.1524)
				(type default)
			)
			(layer "F.SilkS")
		)
		(fp_line
			(start 0.7874 0.4064)
			(end -0.7874 0.4064)
			(stroke
				(width 0.1524)
				(type default)
			)
			(layer "F.SilkS")
		)
		(fp_line
			(start -0.7874 -0.4064)
			(end 0.7874 -0.4064)
			(stroke
				(width 0.1524)
				(type default)
			)
			(layer "F.SilkS")
		)
		(fp_line
			(start 0.7874 -0.4064)
			(end 0.7874 0.4064)
			(stroke
				(width 0.1524)
				(type default)
			)
			(layer "F.SilkS")
		)
		(fp_line
			(start -0.67945 0.3048)
			(end -0.67945 -0.305054)
			(stroke
				(width 0.1)
				(type default)
			)
			(layer "F.Fab")
		)
		(fp_line
			(start -0.12065 0.3048)
			(end -0.67945 0.3048)
			(stroke
				(width 0.1)
				(type default)
			)
			(layer "F.Fab")
		)
		(fp_line
			(start 0.120396 0.3048)
			(end 0.120396 0.2794)
			(stroke
				(width 0.1)
				(type default)
			)
			(layer "F.Fab")
		)
		(fp_line
			(start 0.67945 0.3048)
			(end 0.120396 0.3048)
			(stroke
				(width 0.1)
				(type default)
			)
			(layer "F.Fab")
		)
		(fp_line
			(start -0.12065 0.2794)
			(end -0.12065 0.3048)
			(stroke
				(width 0.1)
				(type default)
			)
			(layer "F.Fab")
		)
		(fp_line
			(start 0.120396 0.2794)
			(end -0.12065 0.2794)
			(stroke
				(width 0.1)
				(type default)
			)
			(layer "F.Fab")
		)
		(fp_line
			(start -0.12065 -0.2794)
			(end 0.12065 -0.2794)
			(stroke
				(width 0.1)
				(type default)
			)
			(layer "F.Fab")
		)
		(fp_line
			(start 0.12065 -0.2794)
			(end 0.12065 -0.3048)
			(stroke
				(width 0.1)
				(type default)
			)
			(layer "F.Fab")
		)
		(fp_line
			(start 0.12065 -0.3048)
			(end 0.67945 -0.3048)
			(stroke
				(width 0.1)
				(type default)
			)
			(layer "F.Fab")
		)
		(fp_line
			(start 0.67945 -0.3048)
			(end 0.67945 0.3048)
			(stroke
				(width 0.1)
				(type default)
			)
			(layer "F.Fab")
		)
		(fp_line
			(start -0.67945 -0.305054)
			(end -0.12065 -0.305054)
			(stroke
				(width 0.1)
				(type default)
			)
			(layer "F.Fab")
		)
		(fp_line
			(start -0.12065 -0.305054)
			(end -0.12065 -0.2794)
			(stroke
				(width 0.1)
				(type default)
			)
			(layer "F.Fab")
		)
		(pad "1" smd circle
			(at -0.40005 0 270)
			(size 0 0)
			(layers "F.Cu" "F.Mask" "F.Paste")
			(net "PD_PCH_GPPC_A_14")
		)
		(pad "2" smd circle
			(at 0.40005 0 270)
			(size 0 0)
			(layers "F.Cu" "F.Mask" "F.Paste")
			(net "GND")
		)
	)
	(footprint ""
		(layer "F.Cu")
		(at 36.956238 -132.79374)
		(property "Reference" "C2452"
			(at 0 0 0)
			(layer "F.SilkS")
			(hide yes)
			(effects
				(font
					(size 1.27 1.27)
				)
			)
		)
		(property "Value" ""
			(at 0 0 0)
			(layer "F.Fab")
			(effects
				(font
					(size 1.27 1.27)
				)
			)
		)
		(duplicate_pad_numbers_are_jumpers no)
		(fp_line
			(start -0.7874 -0.4064)
			(end 0.7874 -0.4064)
			(stroke
				(width 0.1524)
				(type default)
			)
			(layer "F.SilkS")
		)
		(fp_line
			(start -0.7874 0.4064)
			(end -0.7874 -0.4064)
			(stroke
				(width 0.1524)
				(type default)
			)
			(layer "F.SilkS")
		)
		(fp_line
			(start 0.7874 -0.4064)
			(end 0.7874 0.4064)
			(stroke
				(width 0.1524)
				(type default)
			)
			(layer "F.SilkS")
		)
		(fp_line
			(start 0.7874 0.4064)
			(end -0.7874 0.4064)
			(stroke
				(width 0.1524)
				(type default)
			)
			(layer "F.SilkS")
		)
		(fp_line
			(start -0.67945 -0.305054)
			(end -0.12065 -0.305054)
			(stroke
				(width 0.1)
				(type default)
			)
			(layer "F.Fab")
		)
		(fp_line
			(start -0.67945 0.3048)
			(end -0.67945 -0.305054)
			(stroke
				(width 0.1)
				(type default)
			)
			(layer "F.Fab")
		)
		(fp_line
			(start -0.12065 -0.305054)
			(end -0.12065 -0.2794)
			(stroke
				(width 0.1)
				(type default)
			)
			(layer "F.Fab")
		)
		(fp_line
			(start -0.12065 -0.2794)
			(end 0.12065 -0.2794)
			(stroke
				(width 0.1)
				(type default)
			)
			(layer "F.Fab")
		)
		(fp_line
			(start -0.12065 0.2794)
			(end -0.12065 0.3048)
			(stroke
				(width 0.1)
				(type default)
			)
			(layer "F.Fab")
		)
		(fp_line
			(start -0.12065 0.3048)
			(end -0.67945 0.3048)
			(stroke
				(width 0.1)
				(type default)
			)
			(layer "F.Fab")
		)
		(fp_line
			(start 0.120396 0.2794)
			(end -0.12065 0.2794)
			(stroke
				(width 0.1)
				(type default)
			)
			(layer "F.Fab")
		)
		(fp_line
			(start 0.120396 0.3048)
			(end 0.120396 0.2794)
			(stroke
				(width 0.1)
				(type default)
			)
			(layer "F.Fab")
		)
		(fp_line
			(start 0.12065 -0.3048)
			(end 0.67945 -0.3048)
			(stroke
				(width 0.1)
				(type default)
			)
			(layer "F.Fab")
		)
		(fp_line
			(start 0.12065 -0.2794)
			(end 0.12065 -0.3048)
			(stroke
				(width 0.1)
				(type default)
			)
			(layer "F.Fab")
		)
		(fp_line
			(start 0.67945 -0.3048)
			(end 0.67945 0.3048)
			(stroke
				(width 0.1)
				(type default)
			)
			(layer "F.Fab")
		)
		(fp_line
			(start 0.67945 0.3048)
			(end 0.120396 0.3048)
			(stroke
				(width 0.1)
				(type default)
			)
			(layer "F.Fab")
		)
		(pad "1" smd circle
			(at -0.40005 0)
			(size 0 0)
			(layers "F.Cu" "F.Mask" "F.Paste")
			(net "PVCCFA_EHV_CPU1_EN_R")
		)
		(pad "2" smd circle
			(at 0.40005 0)
			(size 0 0)
			(layers "F.Cu" "F.Mask" "F.Paste")
			(net "GND")
		)
	)
)
